FILE_TYPE = CONNECTIVITY;
{Allegro Design Entry HDL 17.2-2016 S081 (4005846) 1/11/2022}
"PAGE_NUMBER" = 49;
0"NC";
1"TP_CPU1_SPARE4";
2"TP_CPU1_PPD";
3"TP_CPU1_SPARE10";
4"TP_CPU1_SPARE8";
5"TP_CPU1_SPARE11";
6"TP_CPU1_SPARE5";
7"TP_CPU1_SPARE9";
8"TP_CPU1_SPARE13";
9"TP_CPU1_SPARE6";
10"TP_CPU1_SPARE7";
11"TP_CPU1_SPARE12";
%"SOCKET4677_AZIF0045P001C01CS"
"6","(925,2500)","0","pure_quanta","I2";
;
PART_NUMBER"DGA^7000023"
VALUE"SOCKET4677_AZIF0045-P001C01CS"
MATERIAL"IO"
PART_TYPE"SMLF"
$LOCATION"U1"
CDS_LMAN_SYM_OUTLINE"-1050,400,1050,-400"
NEEDS_NO_SIZE"TRUE"
CDS_LIB"pure_quanta"
CDS_LOCATION"U1"
$SEC"6"
CDS_SEC"6";
"RSVD163"
$PN"J13"2;
"RSVD95"
$PN"CG60"3;
"RSVD111"
$PN"CK61"4;
"RSVD87"
$PN"CD69"5;
"RSVD8"
$PN"AU52"6;
"RSVD97"
$PN"CH61"7;
"RSVD44"
$PN"BD77"8;
"RSVD159"
$PN"DA70"1;
"RSVD148"
$PN"CW43"9;
"RSVD115"
$PN"CL60"10;
"RSVD119"
$PN"CL70"11;
END.
